(kicad_pcb
	(version 20260206)
	(generator "pcbnew")
	(generator_version "10.0")
	(general
		(thickness 1.6)
		(legacy_teardrops no)
	)
	(paper "A4")
	(title_block
		(title "04192023_DAF0TMB3IC0_F0TG_MB_C_brd_V02_OCP.brd")
		(comment 1 "Grand Teton / footprints 7473-7479 of 8354")
	)
	(layers
		(0 "F.Cu" signal "TOP")
		(4 "In1.Cu" signal "GND")
		(6 "In2.Cu" signal "IN1")
		(8 "In3.Cu" signal "GND1")
		(10 "In4.Cu" signal "IN2")
		(12 "In5.Cu" signal "GND2")
		(14 "In6.Cu" signal "IN3")
		(16 "In7.Cu" signal "GND3")
		(18 "In8.Cu" signal "VCC")
		(20 "In9.Cu" signal "VCC1")
		(22 "In10.Cu" signal "GND4")
		(24 "In11.Cu" signal "IN4")
		(26 "In12.Cu" signal "GND5")
		(28 "In13.Cu" signal "IN5")
		(30 "In14.Cu" signal "GND6")
		(32 "In15.Cu" signal "IN6")
		(34 "In16.Cu" signal "GND7")
		(2 "B.Cu" signal "BOTTOM")
		(9 "F.Adhes" user "F.Adhesive")
		(11 "B.Adhes" user "B.Adhesive")
		(13 "F.Paste" user "Package Geometry/Pastemask Top")
		(15 "B.Paste" user "Package Geometry/Pastemask Bottom")
		(5 "F.SilkS" user "Ref Des/Silkscreen Top")
		(7 "B.SilkS" user "Ref Des/Silkscreen Bottom")
		(1 "F.Mask" user "Board Geometry/Soldermask Top")
		(3 "B.Mask" user "Board Geometry/Soldermask Bottom")
		(17 "Dwgs.User" user "User.Drawings")
		(19 "Cmts.User" user "User.Comments")
		(21 "Eco1.User" user "User.Eco1")
		(23 "Eco2.User" user "User.Eco2")
		(25 "Edge.Cuts" user "Board Geometry/Outline")
		(27 "Margin" user)
		(31 "F.CrtYd" user "Package Geometry/Place Bound Top")
		(29 "B.CrtYd" user "Package Geometry/Place Bound Bottom")
		(35 "F.Fab" user "Ref Des/Assembly Top")
		(33 "B.Fab" user "Ref Des/Assembly Bottom")
	)
	(footprint ""
		(layer "B.Cu")
		(at 276.436582 -195.859146 180)
		(property "Reference" "R1678"
			(at 0 0 0)
			(layer "B.SilkS")
			(hide yes)
			(effects
				(font
					(size 1.27 1.27)
				)
				(justify mirror)
			)
		)
		(property "Value" ""
			(at 0 0 0)
			(layer "B.Fab")
			(effects
				(font
					(size 1.27 1.27)
				)
				(justify mirror)
			)
		)
		(duplicate_pad_numbers_are_jumpers no)
		(fp_line
			(start 0.7874 0.4064)
			(end 0.7874 -0.4064)
			(stroke
				(width 0.1524)
				(type default)
			)
			(layer "B.SilkS")
		)
		(fp_line
			(start 0.7874 -0.4064)
			(end -0.7874 -0.4064)
			(stroke
				(width 0.1524)
				(type default)
			)
			(layer "B.SilkS")
		)
		(fp_line
			(start -0.7874 0.4064)
			(end 0.7874 0.4064)
			(stroke
				(width 0.1524)
				(type default)
			)
			(layer "B.SilkS")
		)
		(fp_line
			(start -0.7874 -0.4064)
			(end -0.7874 0.4064)
			(stroke
				(width 0.1524)
				(type default)
			)
			(layer "B.SilkS")
		)
		(fp_line
			(start 0.67945 0.3048)
			(end 0.67945 -0.305054)
			(stroke
				(width 0.1)
				(type default)
			)
			(layer "B.Fab")
		)
		(fp_line
			(start 0.67945 -0.305054)
			(end 0.12065 -0.305054)
			(stroke
				(width 0.1)
				(type default)
			)
			(layer "B.Fab")
		)
		(fp_line
			(start 0.12065 0.3048)
			(end 0.67945 0.3048)
			(stroke
				(width 0.1)
				(type default)
			)
			(layer "B.Fab")
		)
		(fp_line
			(start 0.12065 0.2794)
			(end 0.12065 0.3048)
			(stroke
				(width 0.1)
				(type default)
			)
			(layer "B.Fab")
		)
		(fp_line
			(start 0.12065 -0.2794)
			(end -0.12065 -0.2794)
			(stroke
				(width 0.1)
				(type default)
			)
			(layer "B.Fab")
		)
		(fp_line
			(start 0.12065 -0.305054)
			(end 0.12065 -0.2794)
			(stroke
				(width 0.1)
				(type default)
			)
			(layer "B.Fab")
		)
		(fp_line
			(start -0.120396 0.3048)
			(end -0.120396 0.2794)
			(stroke
				(width 0.1)
				(type default)
			)
			(layer "B.Fab")
		)
		(fp_line
			(start -0.120396 0.2794)
			(end 0.12065 0.2794)
			(stroke
				(width 0.1)
				(type default)
			)
			(layer "B.Fab")
		)
		(fp_line
			(start -0.12065 -0.2794)
			(end -0.12065 -0.3048)
			(stroke
				(width 0.1)
				(type default)
			)
			(layer "B.Fab")
		)
		(fp_line
			(start -0.12065 -0.3048)
			(end -0.67945 -0.3048)
			(stroke
				(width 0.1)
				(type default)
			)
			(layer "B.Fab")
		)
		(fp_line
			(start -0.67945 0.3048)
			(end -0.120396 0.3048)
			(stroke
				(width 0.1)
				(type default)
			)
			(layer "B.Fab")
		)
		(fp_line
			(start -0.67945 -0.3048)
			(end -0.67945 0.3048)
			(stroke
				(width 0.1)
				(type default)
			)
			(layer "B.Fab")
		)
		(pad "1" smd circle
			(at 0.40005 0)
			(size 0 0)
			(layers "B.Cu" "B.Mask" "B.Paste")
			(net "I3C_SPD_DDRAF_CPU0_SDA")
		)
		(pad "2" smd circle
			(at -0.40005 0)
			(size 0 0)
			(layers "B.Cu" "B.Mask" "B.Paste")
			(net "I3C_SPD_DDRE_CPU0_SDA")
		)
	)
	(footprint ""
		(layer "B.Cu")
		(at 218.059 -340.868 180)
		(property "Reference" "R6748"
			(at 0 0 0)
			(layer "B.SilkS")
			(hide yes)
			(effects
				(font
					(size 1.27 1.27)
				)
				(justify mirror)
			)
		)
		(property "Value" ""
			(at 0 0 0)
			(layer "B.Fab")
			(effects
				(font
					(size 1.27 1.27)
				)
				(justify mirror)
			)
		)
		(duplicate_pad_numbers_are_jumpers no)
		(fp_line
			(start 0.32512 0.175006)
			(end 0.32512 -0.175006)
			(stroke
				(width 0.1)
				(type default)
			)
			(layer "B.Fab")
		)
		(fp_line
			(start 0.32512 -0.175006)
			(end -0.32512 -0.175006)
			(stroke
				(width 0.1)
				(type default)
			)
			(layer "B.Fab")
		)
		(fp_line
			(start -0.32512 0.175006)
			(end 0.32512 0.175006)
			(stroke
				(width 0.1)
				(type default)
			)
			(layer "B.Fab")
		)
		(fp_line
			(start -0.32512 -0.175006)
			(end -0.32512 0.175006)
			(stroke
				(width 0.1)
				(type default)
			)
			(layer "B.Fab")
		)
		(pad "1" smd rect
			(at 0.2667 0)
			(size 0.3048 0.381)
			(layers "B.Cu" "B.Mask" "B.Paste")
			(net "SMB_RT_CPU1_P2_R_SDA")
		)
		(pad "2" smd rect
			(at -0.2667 0 180)
			(size 0.3048 0.381)
			(layers "B.Cu" "B.Mask" "B.Paste")
			(net "SMB_RT_CPU1_P2_SDA")
		)
	)
	(footprint ""
		(layer "B.Cu")
		(at 107.429554 -184.906412 90)
		(property "Reference" "PC105"
			(at 5.990336 1.013714 270)
			(unlocked yes)
			(layer "B.SilkS")
			(effects
				(font
					(size 0.7874 0.5842)
					(thickness 0.1524)
				)
				(justify left mirror)
			)
		)
		(property "Value" ""
			(at 0 0 90)
			(layer "B.Fab")
			(effects
				(font
					(size 1.27 1.27)
				)
				(justify mirror)
			)
		)
		(duplicate_pad_numbers_are_jumpers no)
		(fp_line
			(start 4.533392 -2.249932)
			(end -4.533392 -2.249932)
			(stroke
				(width 0.1524)
				(type default)
			)
			(layer "B.SilkS")
		)
		(fp_line
			(start -4.533392 -2.249932)
			(end -4.533392 2.249932)
			(stroke
				(width 0.1524)
				(type default)
			)
			(layer "B.SilkS")
		)
		(fp_line
			(start 4.533392 2.249932)
			(end 4.533392 -2.249932)
			(stroke
				(width 0.1524)
				(type default)
			)
			(layer "B.SilkS")
		)
		(fp_line
			(start -4.533392 2.249932)
			(end 4.533392 2.249932)
			(stroke
				(width 0.1524)
				(type default)
			)
			(layer "B.SilkS")
		)
		(fp_rect
			(start 4.533392 -2.326132)
			(end 5.39242 2.326132)
			(stroke
				(width 0)
				(type default)
			)
			(fill yes)
			(layer "B.SilkS")
		)
		(fp_line
			(start 3.750056 -2.249932)
			(end -3.750056 -2.249932)
			(stroke
				(width 0.1)
				(type default)
			)
			(layer "B.Fab")
		)
		(fp_line
			(start -3.750056 -2.249932)
			(end -3.750056 2.249932)
			(stroke
				(width 0.1)
				(type default)
			)
			(layer "B.Fab")
		)
		(fp_line
			(start 3.750056 2.249932)
			(end 3.750056 -2.249932)
			(stroke
				(width 0.1)
				(type default)
			)
			(layer "B.Fab")
		)
		(fp_line
			(start -3.750056 2.249932)
			(end 3.750056 2.249932)
			(stroke
				(width 0.1)
				(type default)
			)
			(layer "B.Fab")
		)
		(fp_text user "-"
			(at -4.8514 -0.14605 90)
			(unlocked yes)
			(layer "B.SilkS")
			(effects
				(font
					(size 1.905 1.4224)
					(thickness 0.1524)
				)
				(justify left mirror)
			)
		)
		(fp_text user "+"
			(at 6.322314 0.786384 0)
			(unlocked yes)
			(layer "B.SilkS")
			(effects
				(font
					(size 1.905 1.4224)
					(thickness 0.1524)
				)
				(justify left mirror)
			)
		)
		(fp_text user "-"
			(at -4.8514 -0.14605 90)
			(unlocked yes)
			(layer "B.Fab")
			(effects
				(font
					(size 1.905 1.4224)
					(thickness 0.1524)
				)
				(justify left mirror)
			)
		)
		(fp_text user "+"
			(at 6.322314 0.786384 0)
			(unlocked yes)
			(layer "B.Fab")
			(effects
				(font
					(size 1.905 1.4224)
					(thickness 0.1524)
				)
				(justify left mirror)
			)
		)
		(pad "1" smd rect
			(at 3.199892 0 270)
			(size 2.413 2.8194)
			(layers "B.Cu" "B.Mask" "B.Paste")
			(net "PVDDCR_CPU0_P1")
		)
		(pad "2" smd rect
			(at -3.199892 0 270)
			(size 2.413 2.8194)
			(layers "B.Cu" "B.Mask" "B.Paste")
			(net "GND")
		)
	)
	(footprint ""
		(layer "B.Cu")
		(at 355.009958 -245.487952 180)
		(property "Reference" "C252"
			(at 0 0 0)
			(layer "B.SilkS")
			(hide yes)
			(effects
				(font
					(size 1.27 1.27)
				)
				(justify mirror)
			)
		)
		(property "Value" ""
			(at 0 0 0)
			(layer "B.Fab")
			(effects
				(font
					(size 1.27 1.27)
				)
				(justify mirror)
			)
		)
		(duplicate_pad_numbers_are_jumpers no)
		(fp_line
			(start 0.7874 0.4064)
			(end 0.7874 -0.4064)
			(stroke
				(width 0.1524)
				(type default)
			)
			(layer "B.SilkS")
		)
		(fp_line
			(start 0.7874 -0.4064)
			(end -0.7874 -0.4064)
			(stroke
				(width 0.1524)
				(type default)
			)
			(layer "B.SilkS")
		)
		(fp_line
			(start -0.7874 0.4064)
			(end 0.7874 0.4064)
			(stroke
				(width 0.1524)
				(type default)
			)
			(layer "B.SilkS")
		)
		(fp_line
			(start -0.7874 -0.4064)
			(end -0.7874 0.4064)
			(stroke
				(width 0.1524)
				(type default)
			)
			(layer "B.SilkS")
		)
		(fp_line
			(start 0.67945 0.3048)
			(end 0.67945 -0.305054)
			(stroke
				(width 0.1)
				(type default)
			)
			(layer "B.Fab")
		)
		(fp_line
			(start 0.67945 -0.305054)
			(end 0.12065 -0.305054)
			(stroke
				(width 0.1)
				(type default)
			)
			(layer "B.Fab")
		)
		(fp_line
			(start 0.12065 0.3048)
			(end 0.67945 0.3048)
			(stroke
				(width 0.1)
				(type default)
			)
			(layer "B.Fab")
		)
		(fp_line
			(start 0.12065 0.2794)
			(end 0.12065 0.3048)
			(stroke
				(width 0.1)
				(type default)
			)
			(layer "B.Fab")
		)
		(fp_line
			(start 0.12065 -0.2794)
			(end -0.12065 -0.2794)
			(stroke
				(width 0.1)
				(type default)
			)
			(layer "B.Fab")
		)
		(fp_line
			(start 0.12065 -0.305054)
			(end 0.12065 -0.2794)
			(stroke
				(width 0.1)
				(type default)
			)
			(layer "B.Fab")
		)
		(fp_line
			(start -0.120396 0.3048)
			(end -0.120396 0.2794)
			(stroke
				(width 0.1)
				(type default)
			)
			(layer "B.Fab")
		)
		(fp_line
			(start -0.120396 0.2794)
			(end 0.12065 0.2794)
			(stroke
				(width 0.1)
				(type default)
			)
			(layer "B.Fab")
		)
		(fp_line
			(start -0.12065 -0.2794)
			(end -0.12065 -0.3048)
			(stroke
				(width 0.1)
				(type default)
			)
			(layer "B.Fab")
		)
		(fp_line
			(start -0.12065 -0.3048)
			(end -0.67945 -0.3048)
			(stroke
				(width 0.1)
				(type default)
			)
			(layer "B.Fab")
		)
		(fp_line
			(start -0.67945 0.3048)
			(end -0.120396 0.3048)
			(stroke
				(width 0.1)
				(type default)
			)
			(layer "B.Fab")
		)
		(fp_line
			(start -0.67945 -0.3048)
			(end -0.67945 0.3048)
			(stroke
				(width 0.1)
				(type default)
			)
			(layer "B.Fab")
		)
		(pad "1" smd circle
			(at 0.40005 0)
			(size 0 0)
			(layers "B.Cu" "B.Mask" "B.Paste")
			(net "PVDDCR_CPU0_P0")
		)
		(pad "2" smd circle
			(at -0.40005 0)
			(size 0 0)
			(layers "B.Cu" "B.Mask" "B.Paste")
			(net "GND")
		)
	)
	(footprint ""
		(layer "B.Cu")
		(at 428.211742 -193.99631)
		(property "Reference" "R98"
			(at 0 0 0)
			(layer "B.SilkS")
			(hide yes)
			(effects
				(font
					(size 1.27 1.27)
				)
				(justify mirror)
			)
		)
		(property "Value" ""
			(at 0 0 0)
			(layer "B.Fab")
			(effects
				(font
					(size 1.27 1.27)
				)
				(justify mirror)
			)
		)
		(duplicate_pad_numbers_are_jumpers no)
		(fp_line
			(start -0.7874 -0.4064)
			(end -0.7874 0.4064)
			(stroke
				(width 0.1524)
				(type default)
			)
			(layer "B.SilkS")
		)
		(fp_line
			(start -0.7874 0.4064)
			(end 0.7874 0.4064)
			(stroke
				(width 0.1524)
				(type default)
			)
			(layer "B.SilkS")
		)
		(fp_line
			(start 0.7874 -0.4064)
			(end -0.7874 -0.4064)
			(stroke
				(width 0.1524)
				(type default)
			)
			(layer "B.SilkS")
		)
		(fp_line
			(start 0.7874 0.4064)
			(end 0.7874 -0.4064)
			(stroke
				(width 0.1524)
				(type default)
			)
			(layer "B.SilkS")
		)
		(fp_line
			(start -0.67945 -0.3048)
			(end -0.67945 0.3048)
			(stroke
				(width 0.1)
				(type default)
			)
			(layer "B.Fab")
		)
		(fp_line
			(start -0.67945 0.3048)
			(end -0.120396 0.3048)
			(stroke
				(width 0.1)
				(type default)
			)
			(layer "B.Fab")
		)
		(fp_line
			(start -0.12065 -0.3048)
			(end -0.67945 -0.3048)
			(stroke
				(width 0.1)
				(type default)
			)
			(layer "B.Fab")
		)
		(fp_line
			(start -0.12065 -0.2794)
			(end -0.12065 -0.3048)
			(stroke
				(width 0.1)
				(type default)
			)
			(layer "B.Fab")
		)
		(fp_line
			(start -0.120396 0.2794)
			(end 0.12065 0.2794)
			(stroke
				(width 0.1)
				(type default)
			)
			(layer "B.Fab")
		)
		(fp_line
			(start -0.120396 0.3048)
			(end -0.120396 0.2794)
			(stroke
				(width 0.1)
				(type default)
			)
			(layer "B.Fab")
		)
		(fp_line
			(start 0.12065 -0.305054)
			(end 0.12065 -0.2794)
			(stroke
				(width 0.1)
				(type default)
			)
			(layer "B.Fab")
		)
		(fp_line
			(start 0.12065 -0.2794)
			(end -0.12065 -0.2794)
			(stroke
				(width 0.1)
				(type default)
			)
			(layer "B.Fab")
		)
		(fp_line
			(start 0.12065 0.2794)
			(end 0.12065 0.3048)
			(stroke
				(width 0.1)
				(type default)
			)
			(layer "B.Fab")
		)
		(fp_line
			(start 0.12065 0.3048)
			(end 0.67945 0.3048)
			(stroke
				(width 0.1)
				(type default)
			)
			(layer "B.Fab")
		)
		(fp_line
			(start 0.67945 -0.305054)
			(end 0.12065 -0.305054)
			(stroke
				(width 0.1)
				(type default)
			)
			(layer "B.Fab")
		)
		(fp_line
			(start 0.67945 0.3048)
			(end 0.67945 -0.305054)
			(stroke
				(width 0.1)
				(type default)
			)
			(layer "B.Fab")
		)
		(pad "1" smd circle
			(at 0.40005 0 180)
			(size 0 0)
			(layers "B.Cu" "B.Mask" "B.Paste")
			(net "P3V3")
		)
		(pad "2" smd circle
			(at -0.40005 0 180)
			(size 0 0)
			(layers "B.Cu" "B.Mask" "B.Paste")
			(net "PWRGD_CHI_CPU0_DIMM")
		)
	)
	(footprint ""
		(layer "B.Cu")
		(at 369.519454 -266.00531)
		(property "Reference" "C2600"
			(at 0 0 0)
			(layer "B.SilkS")
			(hide yes)
			(effects
				(font
					(size 1.27 1.27)
				)
				(justify mirror)
			)
		)
		(property "Value" ""
			(at 0 0 0)
			(layer "B.Fab")
			(effects
				(font
					(size 1.27 1.27)
				)
				(justify mirror)
			)
		)
		(duplicate_pad_numbers_are_jumpers no)
		(fp_line
			(start -0.7874 -0.4064)
			(end -0.7874 0.4064)
			(stroke
				(width 0.1524)
				(type default)
			)
			(layer "B.SilkS")
		)
		(fp_line
			(start -0.7874 0.4064)
			(end 0.7874 0.4064)
			(stroke
				(width 0.1524)
				(type default)
			)
			(layer "B.SilkS")
		)
		(fp_line
			(start 0.7874 -0.4064)
			(end -0.7874 -0.4064)
			(stroke
				(width 0.1524)
				(type default)
			)
			(layer "B.SilkS")
		)
		(fp_line
			(start 0.7874 0.4064)
			(end 0.7874 -0.4064)
			(stroke
				(width 0.1524)
				(type default)
			)
			(layer "B.SilkS")
		)
		(fp_line
			(start -0.67945 -0.3048)
			(end -0.67945 0.3048)
			(stroke
				(width 0.1)
				(type default)
			)
			(layer "B.Fab")
		)
		(fp_line
			(start -0.67945 0.3048)
			(end -0.120396 0.3048)
			(stroke
				(width 0.1)
				(type default)
			)
			(layer "B.Fab")
		)
		(fp_line
			(start -0.12065 -0.3048)
			(end -0.67945 -0.3048)
			(stroke
				(width 0.1)
				(type default)
			)
			(layer "B.Fab")
		)
		(fp_line
			(start -0.12065 -0.2794)
			(end -0.12065 -0.3048)
			(stroke
				(width 0.1)
				(type default)
			)
			(layer "B.Fab")
		)
		(fp_line
			(start -0.120396 0.2794)
			(end 0.12065 0.2794)
			(stroke
				(width 0.1)
				(type default)
			)
			(layer "B.Fab")
		)
		(fp_line
			(start -0.120396 0.3048)
			(end -0.120396 0.2794)
			(stroke
				(width 0.1)
				(type default)
			)
			(layer "B.Fab")
		)
		(fp_line
			(start 0.12065 -0.305054)
			(end 0.12065 -0.2794)
			(stroke
				(width 0.1)
				(type default)
			)
			(layer "B.Fab")
		)
		(fp_line
			(start 0.12065 -0.2794)
			(end -0.12065 -0.2794)
			(stroke
				(width 0.1)
				(type default)
			)
			(layer "B.Fab")
		)
		(fp_line
			(start 0.12065 0.2794)
			(end 0.12065 0.3048)
			(stroke
				(width 0.1)
				(type default)
			)
			(layer "B.Fab")
		)
		(fp_line
			(start 0.12065 0.3048)
			(end 0.67945 0.3048)
			(stroke
				(width 0.1)
				(type default)
			)
			(layer "B.Fab")
		)
		(fp_line
			(start 0.67945 -0.305054)
			(end 0.12065 -0.305054)
			(stroke
				(width 0.1)
				(type default)
			)
			(layer "B.Fab")
		)
		(fp_line
			(start 0.67945 0.3048)
			(end 0.67945 -0.305054)
			(stroke
				(width 0.1)
				(type default)
			)
			(layer "B.Fab")
		)
		(pad "1" smd circle
			(at 0.40005 0 180)
			(size 0 0)
			(layers "B.Cu" "B.Mask" "B.Paste")
			(net "PVDD11_S3_P0")
		)
		(pad "2" smd circle
			(at -0.40005 0 180)
			(size 0 0)
			(layers "B.Cu" "B.Mask" "B.Paste")
			(net "GND")
		)
	)
	(footprint ""
		(layer "B.Cu")
		(at 101.385878 -145.64741)
		(property "Reference" "R8168"
			(at 0 0 0)
			(layer "B.SilkS")
			(hide yes)
			(effects
				(font
					(size 1.27 1.27)
				)
				(justify mirror)
			)
		)
		(property "Value" ""
			(at 0 0 0)
			(layer "B.Fab")
			(effects
				(font
					(size 1.27 1.27)
				)
				(justify mirror)
			)
		)
		(duplicate_pad_numbers_are_jumpers no)
		(fp_line
			(start -0.7874 -0.4064)
			(end -0.7874 0.4064)
			(stroke
				(width 0.1524)
				(type default)
			)
			(layer "B.SilkS")
		)
		(fp_line
			(start -0.7874 0.4064)
			(end 0.7874 0.4064)
			(stroke
				(width 0.1524)
				(type default)
			)
			(layer "B.SilkS")
		)
		(fp_line
			(start 0.7874 -0.4064)
			(end -0.7874 -0.4064)
			(stroke
				(width 0.1524)
				(type default)
			)
			(layer "B.SilkS")
		)
		(fp_line
			(start 0.7874 0.4064)
			(end 0.7874 -0.4064)
			(stroke
				(width 0.1524)
				(type default)
			)
			(layer "B.SilkS")
		)
		(fp_line
			(start -0.67945 -0.3048)
			(end -0.67945 0.3048)
			(stroke
				(width 0.1)
				(type default)
			)
			(layer "B.Fab")
		)
		(fp_line
			(start -0.67945 0.3048)
			(end -0.120396 0.3048)
			(stroke
				(width 0.1)
				(type default)
			)
			(layer "B.Fab")
		)
		(fp_line
			(start -0.12065 -0.3048)
			(end -0.67945 -0.3048)
			(stroke
				(width 0.1)
				(type default)
			)
			(layer "B.Fab")
		)
		(fp_line
			(start -0.12065 -0.2794)
			(end -0.12065 -0.3048)
			(stroke
				(width 0.1)
				(type default)
			)
			(layer "B.Fab")
		)
		(fp_line
			(start -0.120396 0.2794)
			(end 0.12065 0.2794)
			(stroke
				(width 0.1)
				(type default)
			)
			(layer "B.Fab")
		)
		(fp_line
			(start -0.120396 0.3048)
			(end -0.120396 0.2794)
			(stroke
				(width 0.1)
				(type default)
			)
			(layer "B.Fab")
		)
		(fp_line
			(start 0.12065 -0.305054)
			(end 0.12065 -0.2794)
			(stroke
				(width 0.1)
				(type default)
			)
			(layer "B.Fab")
		)
		(fp_line
			(start 0.12065 -0.2794)
			(end -0.12065 -0.2794)
			(stroke
				(width 0.1)
				(type default)
			)
			(layer "B.Fab")
		)
		(fp_line
			(start 0.12065 0.2794)
			(end 0.12065 0.3048)
			(stroke
				(width 0.1)
				(type default)
			)
			(layer "B.Fab")
		)
		(fp_line
			(start 0.12065 0.3048)
			(end 0.67945 0.3048)
			(stroke
				(width 0.1)
				(type default)
			)
			(layer "B.Fab")
		)
		(fp_line
			(start 0.67945 -0.305054)
			(end 0.12065 -0.305054)
			(stroke
				(width 0.1)
				(type default)
			)
			(layer "B.Fab")
		)
		(fp_line
			(start 0.67945 0.3048)
			(end 0.67945 -0.305054)
			(stroke
				(width 0.1)
				(type default)
			)
			(layer "B.Fab")
		)
		(pad "1" smd circle
			(at 0.40005 0 180)
			(size 0 0)
			(layers "B.Cu" "B.Mask" "B.Paste")
			(net "PVDDCR_CPU0_P1_OCP_N")
		)
		(pad "2" smd circle
			(at -0.40005 0 180)
			(size 0 0)
			(layers "B.Cu" "B.Mask" "B.Paste")
			(net "PVDDCR_CPU0_P1_OCP_N_R")
		)
	)
)
